(kicad_pcb
	(version 20260206)
	(generator "pcbnew")
	(generator_version "10.0")
	(general
		(thickness 1.6)
		(legacy_teardrops no)
	)
	(paper "A4")
	(title_block
		(title "01162023_DA0F0TEBIF0_F0T_Expander_BD_F_brd_V02_OCP.brd")
		(comment 1 "Grand Teton / footprints 6941-6941 of 9728")
	)
	(layers
		(0 "F.Cu" signal "TOP")
		(4 "In1.Cu" signal "GND")
		(6 "In2.Cu" signal "VCC")
		(8 "In3.Cu" signal "VCC1")
		(10 "In4.Cu" signal "GND1")
		(12 "In5.Cu" signal "IN1")
		(14 "In6.Cu" signal "GND2")
		(16 "In7.Cu" signal "IN2")
		(18 "In8.Cu" signal "GND3")
		(20 "In9.Cu" signal "IN3")
		(22 "In10.Cu" signal "GND4")
		(24 "In11.Cu" signal "IN4")
		(26 "In12.Cu" signal "GND5")
		(28 "In13.Cu" signal "IN5")
		(30 "In14.Cu" signal "GND6")
		(32 "In15.Cu" signal "IN6")
		(34 "In16.Cu" signal "GND7")
		(2 "B.Cu" signal "BOTTOM")
		(9 "F.Adhes" user "F.Adhesive")
		(11 "B.Adhes" user "B.Adhesive")
		(13 "F.Paste" user "Package Geometry/Pastemask Top")
		(15 "B.Paste" user "Package Geometry/Pastemask Bottom")
		(5 "F.SilkS" user "Ref Des/Silkscreen Top")
		(7 "B.SilkS" user "Ref Des/Silkscreen Bottom")
		(1 "F.Mask" user "Board Geometry/Soldermask Top")
		(3 "B.Mask" user "Board Geometry/Soldermask Bottom")
		(17 "Dwgs.User" user "User.Drawings")
		(19 "Cmts.User" user "User.Comments")
		(21 "Eco1.User" user "User.Eco1")
		(23 "Eco2.User" user "User.Eco2")
		(25 "Edge.Cuts" user "Board Geometry/Outline")
		(27 "Margin" user)
		(31 "F.CrtYd" user "Package Geometry/Place Bound Top")
		(29 "B.CrtYd" user "Package Geometry/Place Bound Bottom")
		(35 "F.Fab" user "Ref Des/Assembly Top")
		(33 "B.Fab" user "Ref Des/Assembly Bottom")
	)
	(footprint ""
		(layer "F.Cu")
		(at 230.724964 -64.200024 180)
		(property "Reference" "J2"
			(at -5.4356 -8.346948 180)
			(unlocked yes)
			(layer "F.SilkS")
			(effects
				(font
					(size 0.7874 0.5842)
					(thickness 0.1524)
				)
				(justify left)
			)
		)
		(property "Value" ""
			(at 0 0 180)
			(layer "F.Fab")
			(effects
				(font
					(size 1.27 1.27)
				)
			)
		)
		(duplicate_pad_numbers_are_jumpers no)
		(fp_line
			(start 4.872482 7.649972)
			(end 4.872482 -7.649972)
			(stroke
				(width 0.1524)
				(type default)
			)
			(layer "F.SilkS")
		)
		(fp_line
			(start 4.872482 -7.649972)
			(end -5.377434 -7.649972)
			(stroke
				(width 0.1524)
				(type default)
			)
			(layer "F.SilkS")
		)
		(fp_line
			(start 3.927602 6.83006)
			(end 3.4544 6.83006)
			(stroke
				(width 0.1524)
				(type default)
			)
			(layer "F.SilkS")
		)
		(fp_line
			(start 3.927602 6.5024)
			(end 3.927602 6.83006)
			(stroke
				(width 0.1524)
				(type default)
			)
			(layer "F.SilkS")
		)
		(fp_line
			(start 3.927602 -5.6896)
			(end 3.927602 5.715)
			(stroke
				(width 0.1524)
				(type default)
			)
			(layer "F.SilkS")
		)
		(fp_line
			(start 3.927602 -6.83006)
			(end 3.927602 -6.5024)
			(stroke
				(width 0.1524)
				(type default)
			)
			(layer "F.SilkS")
		)
		(fp_line
			(start 3.4544 -6.83006)
			(end 3.927602 -6.83006)
			(stroke
				(width 0.1524)
				(type default)
			)
			(layer "F.SilkS")
		)
		(fp_line
			(start 3.1877 6.83006)
			(end -3.0988 6.83006)
			(stroke
				(width 0.1524)
				(type default)
			)
			(layer "F.SilkS")
		)
		(fp_line
			(start -3.0988 -6.83006)
			(end 3.1496 -6.83006)
			(stroke
				(width 0.1524)
				(type default)
			)
			(layer "F.SilkS")
		)
		(fp_line
			(start -3.927602 5.8674)
			(end -3.927602 -5.8674)
			(stroke
				(width 0.1524)
				(type default)
			)
			(layer "F.SilkS")
		)
		(fp_line
			(start -5.377434 7.649972)
			(end 4.872482 7.649972)
			(stroke
				(width 0.1524)
				(type default)
			)
			(layer "F.SilkS")
		)
		(fp_line
			(start -5.377434 -7.649972)
			(end -5.377434 7.649972)
			(stroke
				(width 0.1524)
				(type default)
			)
			(layer "F.SilkS")
		)
		(fp_poly
			(pts
				(xy -6.475476 -5.90804) (xy -6.475476 -4.89204) (xy -5.459476 -5.40004)
			)
			(stroke
				(width 0)
				(type default)
			)
			(fill yes)
			(layer "F.SilkS")
		)
		(fp_line
			(start 3.927602 6.83006)
			(end -3.927602 6.83006)
			(stroke
				(width 0.1)
				(type default)
			)
			(layer "F.Fab")
		)
		(fp_line
			(start 3.927602 -6.83006)
			(end 3.927602 6.83006)
			(stroke
				(width 0.1)
				(type default)
			)
			(layer "F.Fab")
		)
		(fp_line
			(start -3.927602 6.83006)
			(end -3.927602 -6.83006)
			(stroke
				(width 0.1)
				(type default)
			)
			(layer "F.Fab")
		)
		(fp_line
			(start -3.927602 -6.83006)
			(end 3.927602 -6.83006)
			(stroke
				(width 0.1)
				(type default)
			)
			(layer "F.Fab")
		)
		(fp_poly
			(pts
				(xy -6.475476 -5.90804) (xy -6.475476 -4.89204) (xy -5.459476 -5.40004)
			)
			(stroke
				(width 0)
				(type default)
			)
			(fill yes)
			(layer "F.Fab")
		)
		(pad "" np_thru_hole circle
			(at -0.252476 -5.5499 90)
			(size 1.3208 1.3208)
			(drill 1.3208)
			(layers "*.Cu" "*.Mask")
			(clearance 0.381)
			(thermal_gap 0.381)
		)
		(pad "" np_thru_hole circle
			(at -0.252476 5.5499 90)
			(size 1.3208 1.3208)
			(drill 1.3208)
			(layers "*.Cu" "*.Mask")
			(clearance 0.381)
			(thermal_gap 0.381)
		)
		(pad "A1" smd rect
			(at -1.792478 -5.40004 90)
			(size 0.381 1.3462)
			(layers "F.Cu" "F.Mask" "F.Paste")
			(net "GND")
		)
		(pad "A2" smd rect
			(at -1.792478 -4.800092 90)
			(size 0.381 1.3462)
			(layers "F.Cu" "F.Mask" "F.Paste")
			(net "GND")
		)
		(pad "A3" smd rect
			(at -1.792478 -4.19989 90)
			(size 0.381 1.3462)
			(layers "F.Cu" "F.Mask" "F.Paste")
			(net "GND")
		)
		(pad "A4" smd rect
			(at -1.792478 -3.599942 90)
			(size 0.381 1.3462)
			(layers "F.Cu" "F.Mask" "F.Paste")
			(net "GND")
		)
		(pad "A5" smd rect
			(at -1.792478 -2.999994 90)
			(size 0.381 1.3462)
			(layers "F.Cu" "F.Mask" "F.Paste")
			(net "P5V_AUX")
		)
		(pad "A6" smd rect
			(at -1.792478 -2.400046 90)
			(size 0.381 1.3462)
			(layers "F.Cu" "F.Mask" "F.Paste")
			(net "P5V_AUX")
		)
		(pad "A7" smd rect
			(at -1.792478 -1.800098 90)
			(size 0.381 1.3462)
			(layers "F.Cu" "F.Mask" "F.Paste")
			(net "GND")
		)
		(pad "A8" smd rect
			(at -1.792478 -1.199896 90)
			(size 0.381 1.3462)
			(layers "F.Cu" "F.Mask" "F.Paste")
			(net "P5V_AUX")
		)
		(pad "A9" smd rect
			(at -1.792478 -0.599948 90)
			(size 0.381 1.3462)
			(layers "F.Cu" "F.Mask" "F.Paste")
			(net "P5V_AUX")
		)
		(pad "A10" smd rect
			(at -1.792478 0 90)
			(size 0.381 1.3462)
			(layers "F.Cu" "F.Mask" "F.Paste")
			(net "GND")
		)
		(pad "A11" smd rect
			(at -1.792478 0.599948 90)
			(size 0.381 1.3462)
			(layers "F.Cu" "F.Mask" "F.Paste")
			(net "GND")
		)
		(pad "A12" smd rect
			(at -1.792478 1.199896 90)
			(size 0.381 1.3462)
			(layers "F.Cu" "F.Mask" "F.Paste")
			(net "GND")
		)
		(pad "A13" smd rect
			(at -1.792478 1.800098 90)
			(size 0.381 1.3462)
			(layers "F.Cu" "F.Mask" "F.Paste")
			(net "GND")
		)
		(pad "A14" smd rect
			(at -1.792478 2.400046 90)
			(size 0.381 1.3462)
			(layers "F.Cu" "F.Mask" "F.Paste")
			(net "P5V_AUX")
		)
		(pad "A15" smd rect
			(at -1.792478 2.999994 90)
			(size 0.381 1.3462)
			(layers "F.Cu" "F.Mask" "F.Paste")
			(net "P5V_AUX")
		)
		(pad "A16" smd rect
			(at -1.792478 3.599942 90)
			(size 0.381 1.3462)
			(layers "F.Cu" "F.Mask" "F.Paste")
			(net "GND")
		)
		(pad "A17" smd rect
			(at -1.792478 4.19989 90)
			(size 0.381 1.3462)
			(layers "F.Cu" "F.Mask" "F.Paste")
			(net "P5V_AUX")
		)
		(pad "A18" smd rect
			(at -1.792478 4.800092 90)
			(size 0.381 1.3462)
			(layers "F.Cu" "F.Mask" "F.Paste")
			(net "P5V_AUX")
		)
		(pad "A19" smd rect
			(at -1.792478 5.40004 90)
			(size 0.381 1.3462)
			(layers "F.Cu" "F.Mask" "F.Paste")
			(net "GND")
		)
		(pad "B1" smd rect
			(at 1.287526 -5.40004 90)
			(size 0.381 1.3462)
			(layers "F.Cu" "F.Mask" "F.Paste")
			(net "GND")
		)
		(pad "B2" smd rect
			(at 1.287526 -4.800092 90)
			(size 0.381 1.3462)
			(layers "F.Cu" "F.Mask" "F.Paste")
			(net "USB2_FIO_DP")
		)
		(pad "B3" smd rect
			(at 1.287526 -4.19989 90)
			(size 0.381 1.3462)
			(layers "F.Cu" "F.Mask" "F.Paste")
			(net "USB2_FIO_DN")
		)
		(pad "B4" smd rect
			(at 1.287526 -3.599942 90)
			(size 0.381 1.3462)
			(layers "F.Cu" "F.Mask" "F.Paste")
			(net "GND")
		)
		(pad "B5" smd rect
			(at 1.287526 -2.999994 90)
			(size 0.381 1.3462)
			(layers "F.Cu" "F.Mask" "F.Paste")
			(net "FM_PFR_LED_AMBER_R")
		)
		(pad "B6" smd rect
			(at 1.287526 -2.400046 90)
			(size 0.381 1.3462)
			(layers "F.Cu" "F.Mask" "F.Paste")
			(net "FM_PFR_LED_BLUE_R")
		)
		(pad "B7" smd rect
			(at 1.287526 -1.800098 90)
			(size 0.381 1.3462)
			(layers "F.Cu" "F.Mask" "F.Paste")
			(net "GND")
		)
		(pad "B8" smd rect
			(at 1.287526 -1.199896 90)
			(size 0.381 1.3462)
			(layers "F.Cu" "F.Mask" "F.Paste")
			(net "RST_SMB_FIO_R_N")
		)
		(pad "B9" smd rect
			(at 1.287526 -0.599948 90)
			(size 0.381 1.3462)
			(layers "F.Cu" "F.Mask" "F.Paste")
			(net "PRSNT_DBV2_SLIMSAS")
		)
		(pad "B10" smd rect
			(at 1.287526 0 90)
			(size 0.381 1.3462)
			(layers "F.Cu" "F.Mask" "F.Paste")
			(net "GND")
		)
		(pad "B11" smd rect
			(at 1.287526 0.599948 90)
			(size 0.381 1.3462)
			(layers "F.Cu" "F.Mask" "F.Paste")
			(net "SMB_FIO_R2_SCL")
		)
		(pad "B12" smd rect
			(at 1.287526 1.199896 90)
			(size 0.381 1.3462)
			(layers "F.Cu" "F.Mask" "F.Paste")
			(net "SMB_FIO_R2_SDA")
		)
		(pad "B13" smd rect
			(at 1.287526 1.800098 90)
			(size 0.381 1.3462)
			(layers "F.Cu" "F.Mask" "F.Paste")
			(net "GND")
		)
		(pad "B14" smd rect
			(at 1.287526 2.400046 90)
			(size 0.381 1.3462)
			(layers "F.Cu" "F.Mask" "F.Paste")
			(net "UART_FIO_DEBUG_R_TX")
		)
		(pad "B15" smd rect
			(at 1.287526 2.999994 90)
			(size 0.381 1.3462)
			(layers "F.Cu" "F.Mask" "F.Paste")
			(net "UART_FIO_DEBUG_R_RX")
		)
		(pad "B16" smd rect
			(at 1.287526 3.599942 90)
			(size 0.381 1.3462)
			(layers "F.Cu" "F.Mask" "F.Paste")
			(net "GND")
		)
		(pad "B17" smd rect
			(at 1.287526 4.19989 90)
			(size 0.381 1.3462)
			(layers "F.Cu" "F.Mask" "F.Paste")
			(net "P3V3_AUX")
		)
		(pad "B18" smd rect
			(at 1.287526 4.800092 90)
			(size 0.381 1.3462)
			(layers "F.Cu" "F.Mask" "F.Paste")
			(net "P5V_AUX")
		)
		(pad "B19" smd rect
			(at 1.287526 5.40004 90)
			(size 0.381 1.3462)
			(layers "F.Cu" "F.Mask" "F.Paste")
			(net "GND")
		)
		(pad "G1" thru_hole circle
			(at -3.80238 -6.599936 90)
			(size 1.2192 1.2192)
			(drill 0.8128)
			(layers "*.Cu" "*.Mask")
			(remove_unused_layers no)
			(net "GND")
			(clearance 0.0508)
			(thermal_gap 0.0508)
		)
		(pad "G2" thru_hole circle
			(at -3.80238 6.599936 90)
			(size 1.2192 1.2192)
			(drill 0.8128)
			(layers "*.Cu" "*.Mask")
			(remove_unused_layers no)
			(net "GND")
			(clearance 0.0508)
			(thermal_gap 0.0508)
		)
		(pad "G3" thru_hole circle
			(at 3.297428 -6.100064 90)
			(size 1.2192 1.2192)
			(drill 0.8128)
			(layers "*.Cu" "*.Mask")
			(remove_unused_layers no)
			(net "GND")
			(clearance 0.0508)
			(thermal_gap 0.0508)
		)
		(pad "G4" thru_hole circle
			(at 3.297428 6.100064 90)
			(size 1.2192 1.2192)
			(drill 0.8128)
			(layers "*.Cu" "*.Mask")
			(remove_unused_layers no)
			(net "GND")
			(clearance 0.0508)
			(thermal_gap 0.0508)
		)
		(zone
			(layer "F.Cu")
			(hatch none 0.5)
			(connect_pads
				(clearance 0)
			)
			(min_thickness 0.25)
			(keepout
				(tracks not_allowed)
				(vias allowed)
				(pads allowed)
				(copperpour not_allowed)
				(footprints allowed)
			)
			(placement
				(enabled no)
				(sheetname "")
			)
			(fill
				(thermal_gap 0.5)
				(thermal_bridge_width 0.5)
				(island_removal_mode 0)
			)
			(polygon
				(pts
					(xy 230.377492 -70.600062) (xy 228.27742 -70.600062) (xy 228.27742 -70.000114) (xy 230.377492 -70.000114)
				)
			)
		)
		(zone
			(layer "F.Cu")
			(hatch none 0.5)
			(connect_pads
				(clearance 0)
			)
			(min_thickness 0.25)
			(keepout
				(tracks not_allowed)
				(vias allowed)
				(pads allowed)
				(copperpour not_allowed)
				(footprints allowed)
			)
			(placement
				(enabled no)
				(sheetname "")
			)
			(fill
				(thermal_gap 0.5)
				(thermal_bridge_width 0.5)
				(island_removal_mode 0)
			)
			(polygon
				(pts
					(xy 230.377492 -58.399934) (xy 228.27742 -58.399934) (xy 228.27742 -57.799986) (xy 230.377492 -57.799986)
				)
			)
		)
		(zone
			(layer "F.Cu")
			(hatch none 0.5)
			(connect_pads
				(clearance 0)
			)
			(min_thickness 0.25)
			(keepout
				(tracks not_allowed)
				(vias allowed)
				(pads allowed)
				(copperpour not_allowed)
				(footprints allowed)
			)
			(placement
				(enabled no)
				(sheetname "")
			)
			(fill
				(thermal_gap 0.5)
				(thermal_bridge_width 0.5)
				(island_removal_mode 0)
			)
			(polygon
				(pts
					(xy 233.67746 -70.600062) (xy 231.577388 -70.600062) (xy 231.577388 -70.000114) (xy 233.67746 -70.000114)
				)
			)
		)
		(zone
			(layer "F.Cu")
			(hatch none 0.5)
			(connect_pads
				(clearance 0)
			)
			(min_thickness 0.25)
			(keepout
				(tracks not_allowed)
				(vias allowed)
				(pads allowed)
				(copperpour not_allowed)
				(footprints allowed)
			)
			(placement
				(enabled no)
				(sheetname "")
			)
			(fill
				(thermal_gap 0.5)
				(thermal_bridge_width 0.5)
				(island_removal_mode 0)
			)
			(polygon
				(pts
					(xy 233.67746 -58.399934) (xy 231.577388 -58.399934) (xy 231.577388 -57.799986) (xy 233.67746 -57.799986)
				)
			)
		)
		(zone
			(layer "F.Cu")
			(hatch none 0.5)
			(connect_pads
				(clearance 0)
			)
			(min_thickness 0.25)
			(keepout
				(tracks not_allowed)
				(vias allowed)
				(pads allowed)
				(copperpour not_allowed)
				(footprints allowed)
			)
			(placement
				(enabled no)
				(sheetname "")
			)
			(fill
				(thermal_gap 0.5)
				(thermal_bridge_width 0.5)
				(island_removal_mode 0)
			)
			(polygon
				(pts
					(arc
						(start 227.177346 -57.488836)
						(mid 227.427418 -57.439606)
						(end 227.677472 -57.488836)
					)
					(xy 227.677472 -57.250076) (xy 227.177346 -57.250076)
				)
			)
		)
		(zone
			(layer "F.Cu")
			(hatch none 0.5)
			(connect_pads
				(clearance 0)
			)
			(min_thickness 0.25)
			(keepout
				(tracks not_allowed)
				(vias allowed)
				(pads allowed)
				(copperpour not_allowed)
				(footprints allowed)
			)
			(placement
				(enabled no)
				(sheetname "")
			)
			(fill
				(thermal_gap 0.5)
				(thermal_bridge_width 0.5)
				(island_removal_mode 0)
			)
			(polygon
				(pts
					(arc
						(start 227.677472 -70.911212)
						(mid 227.427418 -70.960346)
						(end 227.177346 -70.911212)
					)
					(xy 227.177346 -71.149972) (xy 227.677472 -71.149972)
				)
			)
		)
		(zone
			(layer "F.Cu")
			(hatch none 0.5)
			(connect_pads
				(clearance 0)
			)
			(min_thickness 0.25)
			(keepout
				(tracks not_allowed)
				(vias allowed)
				(pads allowed)
				(copperpour not_allowed)
				(footprints allowed)
			)
			(placement
				(enabled no)
				(sheetname "")
			)
			(fill
				(thermal_gap 0.5)
				(thermal_bridge_width 0.5)
				(island_removal_mode 0)
			)
			(polygon
				(pts
					(arc
						(start 234.277408 -70.188836)
						(mid 234.52748 -70.139606)
						(end 234.777534 -70.188836)
					)
					(xy 234.777534 -69.950076) (xy 234.277408 -69.950076)
				)
			)
		)
		(zone
			(layer "F.Cu")
			(hatch none 0.5)
			(connect_pads
				(clearance 0)
			)
			(min_thickness 0.25)
			(keepout
				(tracks not_allowed)
				(vias allowed)
				(pads allowed)
				(copperpour not_allowed)
				(footprints allowed)
			)
			(placement
				(enabled no)
				(sheetname "")
			)
			(fill
				(thermal_gap 0.5)
				(thermal_bridge_width 0.5)
				(island_removal_mode 0)
			)
			(polygon
				(pts
					(arc
						(start 234.777534 -58.211212)
						(mid 234.52748 -58.260346)
						(end 234.277408 -58.211212)
					)
					(xy 234.277408 -58.449972) (xy 234.777534 -58.449972)
				)
			)
		)
		(zone
			(layers "F.Cu" "B.Cu" "In1.Cu" "In2.Cu" "In3.Cu" "In4.Cu" "In5.Cu" "In6.Cu"
				"In7.Cu" "In8.Cu" "In9.Cu" "In10.Cu" "In11.Cu" "In12.Cu" "In13.Cu" "In14.Cu"
				"In15.Cu" "In16.Cu"
			)
			(hatch none 0.5)
			(connect_pads
				(clearance 0)
			)
			(min_thickness 0.25)
			(keepout
				(tracks not_allowed)
				(vias allowed)
				(pads allowed)
				(copperpour not_allowed)
				(footprints allowed)
			)
			(placement
				(enabled no)
				(sheetname "")
			)
			(fill
				(thermal_gap 0.5)
				(thermal_bridge_width 0.5)
				(island_removal_mode 0)
			)
			(polygon
				(pts
					(arc
						(start 232.14584 -69.749924)
						(mid 229.80904 -69.749924)
						(end 232.14584 -69.749924)
					)
				)
			)
		)
		(zone
			(layers "F.Cu" "B.Cu" "In1.Cu" "In2.Cu" "In3.Cu" "In4.Cu" "In5.Cu" "In6.Cu"
				"In7.Cu" "In8.Cu" "In9.Cu" "In10.Cu" "In11.Cu" "In12.Cu" "In13.Cu" "In14.Cu"
				"In15.Cu" "In16.Cu"
			)
			(hatch none 0.5)
			(connect_pads
				(clearance 0)
			)
			(min_thickness 0.25)
			(keepout
				(tracks not_allowed)
				(vias allowed)
				(pads allowed)
				(copperpour not_allowed)
				(footprints allowed)
			)
			(placement
				(enabled no)
				(sheetname "")
			)
			(fill
				(thermal_gap 0.5)
				(thermal_bridge_width 0.5)
				(island_removal_mode 0)
			)
			(polygon
				(pts
					(arc
						(start 232.14584 -58.650124)
						(mid 229.80904 -58.650124)
						(end 232.14584 -58.650124)
					)
				)
			)
		)
	)
)
